(kicad_pcb
	(version 20260206)
	(generator "pcbnew")
	(generator_version "10.0")
	(general
		(thickness 1.6)
		(legacy_teardrops no)
	)
	(paper "A4")
	(title_block
		(title "Bryce Canyon_F.DPB_16315-1-OCP.brd")
		(comment 1 "Bryce Canyon / footprints 437-444 of 2223")
	)
	(layers
		(0 "F.Cu" signal "TOP")
		(4 "In1.Cu" signal "L2GND")
		(6 "In2.Cu" signal "L3")
		(8 "In3.Cu" signal "L4GND")
		(10 "In4.Cu" signal "L5")
		(12 "In5.Cu" signal "L6VCC")
		(14 "In6.Cu" signal "L7VCC")
		(16 "In7.Cu" signal "L8")
		(18 "In8.Cu" signal "L9GND")
		(20 "In9.Cu" signal "L10")
		(22 "In10.Cu" signal "L11GND")
		(2 "B.Cu" signal "BOTTOM")
		(9 "F.Adhes" user "F.Adhesive")
		(11 "B.Adhes" user "B.Adhesive")
		(13 "F.Paste" user "Package Geometry/Pastemask Top")
		(15 "B.Paste" user "Package Geometry/Pastemask Bottom")
		(5 "F.SilkS" user "Ref Des/Silkscreen Top")
		(7 "B.SilkS" user "Ref Des/Silkscreen Bottom")
		(1 "F.Mask" user "Board Geometry/Soldermask Top")
		(3 "B.Mask" user "Board Geometry/Soldermask Bottom")
		(17 "Dwgs.User" user "User.Drawings")
		(19 "Cmts.User" user "User.Comments")
		(21 "Eco1.User" user "User.Eco1")
		(23 "Eco2.User" user "User.Eco2")
		(25 "Edge.Cuts" user "Board Geometry/Outline")
		(27 "Margin" user)
		(31 "F.CrtYd" user "Package Geometry/Place Bound Top")
		(29 "B.CrtYd" user "Package Geometry/Place Bound Bottom")
		(35 "F.Fab" user "Ref Des/Assembly Top")
		(33 "B.Fab" user "Ref Des/Assembly Bottom")
	)
	(footprint ""
		(layer "F.Cu")
		(at 109.492796 -168.482518 -90)
		(property "Reference" "R490"
			(at 0 0 270)
			(layer "F.SilkS")
			(hide yes)
			(effects
				(font
					(size 1.27 1.27)
				)
			)
		)
		(property "Value" "300KR2F-GP"
			(at 0.064008 -3.993896 270)
			(unlocked yes)
			(layer "F.Fab")
			(hide yes)
			(effects
				(font
					(size 1.016 1.016)
					(thickness 0.1524)
				)
			)
		)
		(property "Device Type" "R402H16"
			(at 0.064008 -5.517896 270)
			(unlocked yes)
			(layer "F.Fab")
			(hide yes)
			(effects
				(font
					(size 1.016 1.016)
					(thickness 0.1524)
				)
			)
		)
		(duplicate_pad_numbers_are_jumpers no)
		(fp_line
			(start -0.508 -0.9398)
			(end -0.508 0.9398)
			(stroke
				(width 0.1524)
				(type default)
			)
			(layer "F.SilkS")
		)
		(fp_line
			(start 0.508 -0.9398)
			(end -0.508 -0.9398)
			(stroke
				(width 0.1524)
				(type default)
			)
			(layer "F.SilkS")
		)
		(fp_rect
			(start -0.508 0.9398)
			(end 0.508 -0.9398)
			(stroke
				(width 0)
				(type default)
			)
			(fill no)
			(layer "F.CrtYd")
		)
		(fp_rect
			(start -0.508 0.9398)
			(end 0.508 -0.9398)
			(stroke
				(width 0)
				(type default)
			)
			(fill no)
			(layer "F.Fab")
		)
		(pad "1" smd custom
			(at 0 -0.4445 270)
			(size 0.1397 0.1397)
			(layers "F.Cu" "F.Mask" "F.Paste")
			(net "SW_HDD_N15")
			(options
				(clearance outline)
				(anchor circle)
			)
			(primitives
				(gr_poly
					(pts
						(arc
							(start -0.1778 -0.2794)
							(mid -0.249642 -0.249642)
							(end -0.2794 -0.1778)
						)
						(arc
							(start -0.2794 0.1778)
							(mid -0.249642 0.249642)
							(end -0.1778 0.2794)
						)
						(arc
							(start 0.1778 0.2794)
							(mid 0.249642 0.249642)
							(end 0.2794 0.1778)
						)
						(arc
							(start 0.2794 -0.1778)
							(mid 0.249642 -0.249642)
							(end 0.1778 -0.2794)
						)
					)
					(width 0)
					(fill yes)
				)
			)
		)
		(pad "2" smd custom
			(at 0 0.4445 270)
			(size 0.1397 0.1397)
			(layers "F.Cu" "F.Mask" "F.Paste")
			(net "P12V_A")
			(options
				(clearance outline)
				(anchor circle)
			)
			(primitives
				(gr_poly
					(pts
						(arc
							(start -0.1778 -0.2794)
							(mid -0.249642 -0.249642)
							(end -0.2794 -0.1778)
						)
						(arc
							(start -0.2794 0.1778)
							(mid -0.249642 0.249642)
							(end -0.1778 0.2794)
						)
						(arc
							(start 0.1778 0.2794)
							(mid 0.249642 0.249642)
							(end 0.2794 0.1778)
						)
						(arc
							(start 0.2794 -0.1778)
							(mid 0.249642 -0.249642)
							(end 0.1778 -0.2794)
						)
					)
					(width 0)
					(fill yes)
				)
			)
		)
	)
	(footprint ""
		(layer "F.Cu")
		(at 304.0634 -69.6468 180)
		(property "Reference" "R641"
			(at 0 0 180)
			(layer "F.SilkS")
			(hide yes)
			(effects
				(font
					(size 1.27 1.27)
				)
			)
		)
		(property "Value" "0R2J-2-GP"
			(at 0.064008 -3.993896 180)
			(unlocked yes)
			(layer "F.Fab")
			(hide yes)
			(effects
				(font
					(size 1.016 1.016)
					(thickness 0.1524)
				)
			)
		)
		(property "Device Type" "R402H16"
			(at 0.064008 -5.517896 180)
			(unlocked yes)
			(layer "F.Fab")
			(hide yes)
			(effects
				(font
					(size 1.016 1.016)
					(thickness 0.1524)
				)
			)
		)
		(duplicate_pad_numbers_are_jumpers no)
		(fp_line
			(start 0.508 -0.9398)
			(end -0.508 -0.9398)
			(stroke
				(width 0.1524)
				(type default)
			)
			(layer "F.SilkS")
		)
		(fp_line
			(start -0.508 -0.9398)
			(end -0.508 0.9398)
			(stroke
				(width 0.1524)
				(type default)
			)
			(layer "F.SilkS")
		)
		(fp_rect
			(start -0.508 0.9398)
			(end 0.508 -0.9398)
			(stroke
				(width 0)
				(type default)
			)
			(fill no)
			(layer "F.CrtYd")
		)
		(fp_rect
			(start -0.508 0.9398)
			(end 0.508 -0.9398)
			(stroke
				(width 0)
				(type default)
			)
			(fill no)
			(layer "F.Fab")
		)
		(pad "1" smd custom
			(at 0 -0.4445 180)
			(size 0.1397 0.1397)
			(layers "F.Cu" "F.Mask" "F.Paste")
			(net "I2C_BMC_B_COMP_B_SCL_R")
			(options
				(clearance outline)
				(anchor circle)
			)
			(primitives
				(gr_poly
					(pts
						(arc
							(start -0.1778 -0.2794)
							(mid -0.249642 -0.249642)
							(end -0.2794 -0.1778)
						)
						(arc
							(start -0.2794 0.1778)
							(mid -0.249642 0.249642)
							(end -0.1778 0.2794)
						)
						(arc
							(start 0.1778 0.2794)
							(mid 0.249642 0.249642)
							(end 0.2794 0.1778)
						)
						(arc
							(start 0.2794 -0.1778)
							(mid 0.249642 -0.249642)
							(end 0.1778 -0.2794)
						)
					)
					(width 0)
					(fill yes)
				)
			)
		)
		(pad "2" smd custom
			(at 0 0.4445 180)
			(size 0.1397 0.1397)
			(layers "F.Cu" "F.Mask" "F.Paste")
			(net "I2C_BMC_B_COMP_B_SCL_BUF")
			(options
				(clearance outline)
				(anchor circle)
			)
			(primitives
				(gr_poly
					(pts
						(arc
							(start -0.1778 -0.2794)
							(mid -0.249642 -0.249642)
							(end -0.2794 -0.1778)
						)
						(arc
							(start -0.2794 0.1778)
							(mid -0.249642 0.249642)
							(end -0.1778 0.2794)
						)
						(arc
							(start 0.1778 0.2794)
							(mid 0.249642 0.249642)
							(end 0.2794 0.1778)
						)
						(arc
							(start 0.2794 -0.1778)
							(mid 0.249642 -0.249642)
							(end 0.1778 -0.2794)
						)
					)
					(width 0)
					(fill yes)
				)
			)
		)
	)
	(footprint ""
		(layer "F.Cu")
		(at 255.498092 -20.094956 -90)
		(property "Reference" "TP246"
			(at 0 0 270)
			(layer "F.SilkS")
			(hide yes)
			(effects
				(font
					(size 1.27 1.27)
				)
			)
		)
		(property "Value" "TPAD32-GP"
			(at -0.0508 -1.6764 270)
			(unlocked yes)
			(layer "F.Fab")
			(hide yes)
			(effects
				(font
					(size 1.016 1.016)
					(thickness 0.1524)
				)
			)
		)
		(property "Device Type" "TPAD32"
			(at -0.0508 -3.2004 270)
			(unlocked yes)
			(layer "F.Fab")
			(hide yes)
			(effects
				(font
					(size 1.016 1.016)
					(thickness 0.1524)
				)
			)
		)
		(duplicate_pad_numbers_are_jumpers no)
		(fp_poly
			(pts
				(arc
					(start 0 -0.4064)
					(mid 0 0.4064)
					(end 0 -0.4064)
				)
			)
			(stroke
				(width 0)
				(type default)
			)
			(fill no)
			(layer "F.CrtYd")
		)
		(fp_poly
			(pts
				(arc
					(start 0 -0.7112)
					(mid 0 0.7112)
					(end 0 -0.7112)
				)
			)
			(stroke
				(width 0)
				(type default)
			)
			(fill no)
			(layer "F.Fab")
		)
		(pad "1" smd circle
			(at 0 0 270)
			(size 0.8128 0.8128)
			(layers "F.Cu" "F.Mask" "F.Paste")
			(net "TP_PCIE_COMP_A_CLK_N5")
		)
	)
	(footprint ""
		(layer "F.Cu")
		(at 144.6149 -242.25377)
		(property "Reference" "R240"
			(at 0 0 0)
			(layer "F.SilkS")
			(hide yes)
			(effects
				(font
					(size 1.27 1.27)
				)
			)
		)
		(property "Value" "91R3F-1-GP"
			(at -0.0254 -2.5146 0)
			(unlocked yes)
			(layer "F.Fab")
			(hide yes)
			(effects
				(font
					(size 1.016 1.016)
					(thickness 0.1524)
				)
			)
		)
		(property "Device Type" "R603H22"
			(at -0.0254 -4.0386 0)
			(unlocked yes)
			(layer "F.Fab")
			(hide yes)
			(effects
				(font
					(size 1.016 1.016)
					(thickness 0.1524)
				)
			)
		)
		(duplicate_pad_numbers_are_jumpers no)
		(fp_line
			(start -0.4826 0)
			(end -0.2032 0)
			(stroke
				(width 0.2032)
				(type default)
			)
			(layer "F.SilkS")
		)
		(fp_line
			(start 0.2032 0)
			(end 0.4826 0)
			(stroke
				(width 0.2032)
				(type default)
			)
			(layer "F.SilkS")
		)
		(fp_rect
			(start -0.5842 1.3335)
			(end 0.5842 -1.3335)
			(stroke
				(width 0)
				(type default)
			)
			(fill no)
			(layer "F.CrtYd")
		)
		(fp_rect
			(start -0.5842 1.3335)
			(end 0.5842 -1.3335)
			(stroke
				(width 0)
				(type default)
			)
			(fill no)
			(layer "F.Fab")
		)
		(pad "1" smd custom
			(at 0 -0.762)
			(size 0.2159 0.2159)
			(layers "F.Cu" "F.Mask" "F.Paste")
			(net "P5V_A_1")
			(options
				(clearance outline)
				(anchor circle)
			)
			(primitives
				(gr_poly
					(pts
						(arc
							(start -0.3302 -0.4318)
							(mid -0.402042 -0.402042)
							(end -0.4318 -0.3302)
						)
						(arc
							(start -0.4318 0.3302)
							(mid -0.402042 0.402042)
							(end -0.3302 0.4318)
						)
						(arc
							(start 0.3302 0.4318)
							(mid 0.402042 0.402042)
							(end 0.4318 0.3302)
						)
						(arc
							(start 0.4318 -0.3302)
							(mid 0.402042 -0.402042)
							(end 0.3302 -0.4318)
						)
					)
					(width 0)
					(fill yes)
				)
			)
		)
		(pad "2" smd custom
			(at 0 0.762)
			(size 0.2159 0.2159)
			(layers "F.Cu" "F.Mask" "F.Paste")
			(net "DRV_ACT_4")
			(options
				(clearance outline)
				(anchor circle)
			)
			(primitives
				(gr_poly
					(pts
						(arc
							(start -0.3302 -0.4318)
							(mid -0.402042 -0.402042)
							(end -0.4318 -0.3302)
						)
						(arc
							(start -0.4318 0.3302)
							(mid -0.402042 0.402042)
							(end -0.3302 0.4318)
						)
						(arc
							(start 0.3302 0.4318)
							(mid 0.402042 0.402042)
							(end 0.4318 0.3302)
						)
						(arc
							(start 0.4318 -0.3302)
							(mid 0.402042 -0.402042)
							(end 0.3302 -0.4318)
						)
					)
					(width 0)
					(fill yes)
				)
			)
		)
	)
	(footprint ""
		(layer "F.Cu")
		(at 477.719136 -294.679878 90)
		(property "Reference" "R384"
			(at 0 0 90)
			(layer "F.SilkS")
			(hide yes)
			(effects
				(font
					(size 1.27 1.27)
				)
			)
		)
		(property "Value" "2R6F-GP"
			(at -0.0508 -4.8514 90)
			(unlocked yes)
			(layer "F.Fab")
			(hide yes)
			(effects
				(font
					(size 1.016 1.016)
					(thickness 0.1524)
				)
			)
		)
		(property "Device Type" "R1206H26"
			(at 0 -6.3754 90)
			(unlocked yes)
			(layer "F.Fab")
			(hide yes)
			(effects
				(font
					(size 1.016 1.016)
					(thickness 0.1524)
				)
			)
		)
		(duplicate_pad_numbers_are_jumpers no)
		(fp_line
			(start 1.016 -2.2352)
			(end 1.016 2.2352)
			(stroke
				(width 0.1524)
				(type default)
			)
			(layer "F.SilkS")
		)
		(fp_line
			(start -1.016 -2.2352)
			(end 1.016 -2.2352)
			(stroke
				(width 0.1524)
				(type default)
			)
			(layer "F.SilkS")
		)
		(fp_line
			(start 1.016 2.2352)
			(end -1.016 2.2352)
			(stroke
				(width 0.1524)
				(type default)
			)
			(layer "F.SilkS")
		)
		(fp_line
			(start -1.016 2.2352)
			(end -1.016 -2.2352)
			(stroke
				(width 0.1524)
				(type default)
			)
			(layer "F.SilkS")
		)
		(fp_rect
			(start -1.0922 2.3114)
			(end 1.0922 -2.3114)
			(stroke
				(width 0)
				(type default)
			)
			(fill no)
			(layer "F.CrtYd")
		)
		(fp_poly
			(pts
				(xy -1.0922 -2.3114) (xy 1.0922 -2.3114) (xy 1.0922 2.3114) (xy -1.0922 2.3114)
			)
			(stroke
				(width 0)
				(type default)
			)
			(fill no)
			(layer "F.Fab")
		)
		(pad "1" smd rect
			(at 0 -1.397 90)
			(size 1.651 1.27)
			(layers "F.Cu" "F.Mask" "F.Paste")
			(net "P12V_HDD11")
		)
		(pad "2" smd rect
			(at 0 1.397 90)
			(size 1.651 1.27)
			(layers "F.Cu" "F.Mask" "F.Paste")
			(net "12V_PRE_11")
		)
	)
	(footprint ""
		(layer "F.Cu")
		(at 303.8729 -72.3265 -90)
		(property "Reference" "R347"
			(at 0 0 270)
			(layer "F.SilkS")
			(hide yes)
			(effects
				(font
					(size 1.27 1.27)
				)
			)
		)
		(property "Value" "4K7R2F-GP"
			(at 0.064008 -3.993896 270)
			(unlocked yes)
			(layer "F.Fab")
			(hide yes)
			(effects
				(font
					(size 1.016 1.016)
					(thickness 0.1524)
				)
			)
		)
		(property "Device Type" "R402H16"
			(at 0.064008 -5.517896 270)
			(unlocked yes)
			(layer "F.Fab")
			(hide yes)
			(effects
				(font
					(size 1.016 1.016)
					(thickness 0.1524)
				)
			)
		)
		(duplicate_pad_numbers_are_jumpers no)
		(fp_line
			(start -0.508 -0.9398)
			(end -0.508 0.9398)
			(stroke
				(width 0.1524)
				(type default)
			)
			(layer "F.SilkS")
		)
		(fp_line
			(start 0.508 -0.9398)
			(end -0.508 -0.9398)
			(stroke
				(width 0.1524)
				(type default)
			)
			(layer "F.SilkS")
		)
		(fp_rect
			(start -0.508 0.9398)
			(end 0.508 -0.9398)
			(stroke
				(width 0)
				(type default)
			)
			(fill no)
			(layer "F.CrtYd")
		)
		(fp_rect
			(start -0.508 0.9398)
			(end 0.508 -0.9398)
			(stroke
				(width 0)
				(type default)
			)
			(fill no)
			(layer "F.Fab")
		)
		(pad "1" smd custom
			(at 0 -0.4445 270)
			(size 0.1397 0.1397)
			(layers "F.Cu" "F.Mask" "F.Paste")
			(net "TXS0102_B_OE")
			(options
				(clearance outline)
				(anchor circle)
			)
			(primitives
				(gr_poly
					(pts
						(arc
							(start -0.1778 -0.2794)
							(mid -0.249642 -0.249642)
							(end -0.2794 -0.1778)
						)
						(arc
							(start -0.2794 0.1778)
							(mid -0.249642 0.249642)
							(end -0.1778 0.2794)
						)
						(arc
							(start 0.1778 0.2794)
							(mid 0.249642 0.249642)
							(end 0.2794 0.1778)
						)
						(arc
							(start 0.2794 -0.1778)
							(mid 0.249642 -0.249642)
							(end 0.1778 -0.2794)
						)
					)
					(width 0)
					(fill yes)
				)
			)
		)
		(pad "2" smd custom
			(at 0 0.4445 270)
			(size 0.1397 0.1397)
			(layers "F.Cu" "F.Mask" "F.Paste")
			(net "P3V3_STBY_B")
			(options
				(clearance outline)
				(anchor circle)
			)
			(primitives
				(gr_poly
					(pts
						(arc
							(start -0.1778 -0.2794)
							(mid -0.249642 -0.249642)
							(end -0.2794 -0.1778)
						)
						(arc
							(start -0.2794 0.1778)
							(mid -0.249642 0.249642)
							(end -0.1778 0.2794)
						)
						(arc
							(start 0.1778 0.2794)
							(mid 0.249642 0.249642)
							(end 0.2794 0.1778)
						)
						(arc
							(start 0.2794 -0.1778)
							(mid 0.249642 -0.249642)
							(end 0.1778 -0.2794)
						)
					)
					(width 0)
					(fill yes)
				)
			)
		)
	)
	(footprint ""
		(layer "F.Cu")
		(at 250.94438 -256.795778)
		(property "Reference" "C17"
			(at 0 0 0)
			(layer "F.SilkS")
			(hide yes)
			(effects
				(font
					(size 1.27 1.27)
				)
			)
		)
		(property "Value" "SC1U16V3KX-5GP"
			(at 0 -2.8194 0)
			(unlocked yes)
			(layer "F.Fab")
			(hide yes)
			(effects
				(font
					(size 1.016 1.016)
					(thickness 0.1524)
				)
			)
		)
		(property "Device Type" "C603H36"
			(at 0 -4.3434 0)
			(unlocked yes)
			(layer "F.Fab")
			(hide yes)
			(effects
				(font
					(size 1.016 1.016)
					(thickness 0.1524)
				)
			)
		)
		(duplicate_pad_numbers_are_jumpers no)
		(fp_line
			(start 0.508 0)
			(end -0.508 0)
			(stroke
				(width 0.2032)
				(type default)
			)
			(layer "F.SilkS")
		)
		(fp_rect
			(start -0.5842 1.3335)
			(end 0.5842 -1.3335)
			(stroke
				(width 0)
				(type default)
			)
			(fill no)
			(layer "F.CrtYd")
		)
		(fp_rect
			(start -0.5842 1.3335)
			(end 0.5842 -1.3335)
			(stroke
				(width 0)
				(type default)
			)
			(fill no)
			(layer "F.Fab")
		)
		(pad "1" smd custom
			(at 0 -0.762)
			(size 0.2159 0.2159)
			(layers "F.Cu" "F.Mask" "F.Paste")
			(net "P3V3_STBY_A")
			(options
				(clearance outline)
				(anchor circle)
			)
			(primitives
				(gr_poly
					(pts
						(arc
							(start -0.3302 -0.4318)
							(mid -0.402042 -0.402042)
							(end -0.4318 -0.3302)
						)
						(arc
							(start -0.4318 0.3302)
							(mid -0.402042 0.402042)
							(end -0.3302 0.4318)
						)
						(arc
							(start 0.3302 0.4318)
							(mid 0.402042 0.402042)
							(end 0.4318 0.3302)
						)
						(arc
							(start 0.4318 -0.3302)
							(mid 0.402042 -0.402042)
							(end 0.3302 -0.4318)
						)
					)
					(width 0)
					(fill yes)
				)
			)
		)
		(pad "2" smd custom
			(at 0 0.762)
			(size 0.2159 0.2159)
			(layers "F.Cu" "F.Mask" "F.Paste")
			(net "GND")
			(options
				(clearance outline)
				(anchor circle)
			)
			(primitives
				(gr_poly
					(pts
						(arc
							(start -0.3302 -0.4318)
							(mid -0.402042 -0.402042)
							(end -0.4318 -0.3302)
						)
						(arc
							(start -0.4318 0.3302)
							(mid -0.402042 0.402042)
							(end -0.3302 0.4318)
						)
						(arc
							(start 0.3302 0.4318)
							(mid 0.402042 0.402042)
							(end 0.4318 0.3302)
						)
						(arc
							(start 0.4318 -0.3302)
							(mid 0.402042 -0.402042)
							(end 0.3302 -0.4318)
						)
					)
					(width 0)
					(fill yes)
				)
			)
		)
	)
	(footprint ""
		(layer "F.Cu")
		(at 150.311866 -137.371074)
		(property "Reference" "C569"
			(at 0 0 0)
			(layer "F.SilkS")
			(hide yes)
			(effects
				(font
					(size 1.27 1.27)
				)
			)
		)
		(property "Value" "SCD015U25V2KX-GP"
			(at 1.1811 -2.7051 0)
			(unlocked yes)
			(layer "F.Fab")
			(hide yes)
			(effects
				(font
					(size 1.016 1.016)
					(thickness 0.1524)
				)
			)
		)
		(property "Device Type" "C402H22"
			(at 1.1811 -4.2291 0)
			(unlocked yes)
			(layer "F.Fab")
			(hide yes)
			(effects
				(font
					(size 1.016 1.016)
					(thickness 0.1524)
				)
			)
		)
		(duplicate_pad_numbers_are_jumpers no)
		(fp_rect
			(start -0.4318 0.9525)
			(end 0.4318 -0.9525)
			(stroke
				(width 0)
				(type default)
			)
			(fill no)
			(layer "F.CrtYd")
		)
		(fp_rect
			(start -0.4318 0.9525)
			(end 0.4318 -0.9525)
			(stroke
				(width 0)
				(type default)
			)
			(fill no)
			(layer "F.Fab")
		)
		(pad "1" smd custom
			(at 0 -0.4445)
			(size 0.1524 0.1524)
			(layers "F.Cu" "F.Mask" "F.Paste")
			(net "MB0_HS_SENSE_P")
			(options
				(clearance outline)
				(anchor circle)
			)
			(primitives
				(gr_poly
					(pts
						(arc
							(start 0.3048 -0.2032)
							(mid 0.275042 -0.275042)
							(end 0.2032 -0.3048)
						)
						(arc
							(start -0.2032 -0.3048)
							(mid -0.275042 -0.275042)
							(end -0.3048 -0.2032)
						)
						(arc
							(start -0.3048 0.2032)
							(mid -0.275042 0.275042)
							(end -0.2032 0.3048)
						)
						(arc
							(start 0.2032 0.3048)
							(mid 0.275042 0.275042)
							(end 0.3048 0.2032)
						)
					)
					(width 0)
					(fill yes)
				)
			)
		)
		(pad "2" smd custom
			(at 0 0.4445)
			(size 0.1524 0.1524)
			(layers "F.Cu" "F.Mask" "F.Paste")
			(net "MB0_HS_SENSE_N")
			(options
				(clearance outline)
				(anchor circle)
			)
			(primitives
				(gr_poly
					(pts
						(arc
							(start 0.3048 -0.2032)
							(mid 0.275042 -0.275042)
							(end 0.2032 -0.3048)
						)
						(arc
							(start -0.2032 -0.3048)
							(mid -0.275042 -0.275042)
							(end -0.3048 -0.2032)
						)
						(arc
							(start -0.3048 0.2032)
							(mid -0.275042 0.275042)
							(end -0.2032 0.3048)
						)
						(arc
							(start 0.2032 0.3048)
							(mid 0.275042 0.275042)
							(end 0.3048 0.2032)
						)
					)
					(width 0)
					(fill yes)
				)
			)
		)
	)
)
